(kicad_pcb
	(version 20260206)
	(generator "pcbnew")
	(generator_version "10.0")
	(general
		(thickness 1.6)
		(legacy_teardrops no)
	)
	(paper "A4")
	(title_block
		(title "dpb — 14545-sa.0730WZS0815.brd")
		(comment 1 "Honey Badger (Wiwynn) / footprints 571-577 of 1066")
	)
	(layers
		(0 "F.Cu" signal "TOP")
		(4 "In1.Cu" signal "L2GND")
		(6 "In2.Cu" signal "L3")
		(8 "In3.Cu" signal "L4VCC")
		(10 "In4.Cu" signal "L5VCC")
		(12 "In5.Cu" signal "L6")
		(14 "In6.Cu" signal "L7GND")
		(2 "B.Cu" signal "BOTTOM")
		(9 "F.Adhes" user "F.Adhesive")
		(11 "B.Adhes" user "B.Adhesive")
		(13 "F.Paste" user "Package Geometry/Pastemask Top")
		(15 "B.Paste" user "Package Geometry/Pastemask Bottom")
		(5 "F.SilkS" user "Ref Des/Silkscreen Top")
		(7 "B.SilkS" user "Ref Des/Silkscreen Bottom")
		(1 "F.Mask" user "Board Geometry/Soldermask Top")
		(3 "B.Mask" user "Board Geometry/Soldermask Bottom")
		(17 "Dwgs.User" user "User.Drawings")
		(19 "Cmts.User" user "User.Comments")
		(21 "Eco1.User" user "User.Eco1")
		(23 "Eco2.User" user "User.Eco2")
		(25 "Edge.Cuts" user "Board Geometry/Outline")
		(27 "Margin" user)
		(31 "F.CrtYd" user "Package Geometry/Place Bound Top")
		(29 "B.CrtYd" user "Package Geometry/Place Bound Bottom")
		(35 "F.Fab" user "Ref Des/Assembly Top")
		(33 "B.Fab" user "Ref Des/Assembly Bottom")
	)
	(footprint ""
		(layer "F.Cu")
		(at 180.987446 -459.824836)
		(property "Reference" "R387"
			(at 0 0 0)
			(layer "F.SilkS")
			(hide yes)
			(effects
				(font
					(size 1.27 1.27)
				)
			)
		)
		(property "Value" "10KR2F-2-GP"
			(at 0.064008 -3.993896 0)
			(unlocked yes)
			(layer "F.Fab")
			(hide yes)
			(effects
				(font
					(size 1.016 1.016)
					(thickness 0.1524)
				)
			)
		)
		(property "Device Type" "R402H16"
			(at 0.064008 -5.517896 0)
			(unlocked yes)
			(layer "F.Fab")
			(hide yes)
			(effects
				(font
					(size 1.016 1.016)
					(thickness 0.1524)
				)
			)
		)
		(duplicate_pad_numbers_are_jumpers no)
		(fp_line
			(start -0.508 -0.9398)
			(end -0.508 0.9398)
			(stroke
				(width 0.1524)
				(type default)
			)
			(layer "F.SilkS")
		)
		(fp_line
			(start 0.508 -0.9398)
			(end -0.508 -0.9398)
			(stroke
				(width 0.1524)
				(type default)
			)
			(layer "F.SilkS")
		)
		(fp_rect
			(start -0.508 0.9398)
			(end 0.508 -0.9398)
			(stroke
				(width 0)
				(type default)
			)
			(fill no)
			(layer "F.CrtYd")
		)
		(fp_rect
			(start -0.508 0.9398)
			(end 0.508 -0.9398)
			(stroke
				(width 0)
				(type default)
			)
			(fill no)
			(layer "F.Fab")
		)
		(pad "1" smd custom
			(at 0 -0.4445)
			(size 0.1397 0.1397)
			(layers "F.Cu" "F.Mask" "F.Paste")
			(net "P12V")
			(options
				(clearance outline)
				(anchor circle)
			)
			(primitives
				(gr_poly
					(pts
						(arc
							(start -0.1778 -0.2794)
							(mid -0.249642 -0.249642)
							(end -0.2794 -0.1778)
						)
						(arc
							(start -0.2794 0.1778)
							(mid -0.249642 0.249642)
							(end -0.1778 0.2794)
						)
						(arc
							(start 0.1778 0.2794)
							(mid 0.249642 0.249642)
							(end 0.2794 0.1778)
						)
						(arc
							(start 0.2794 -0.1778)
							(mid 0.249642 -0.249642)
							(end 0.1778 -0.2794)
						)
					)
					(width 0)
					(fill yes)
				)
			)
		)
		(pad "2" smd custom
			(at 0 0.4445)
			(size 0.1397 0.1397)
			(layers "F.Cu" "F.Mask" "F.Paste")
			(net "P12V_DIV")
			(options
				(clearance outline)
				(anchor circle)
			)
			(primitives
				(gr_poly
					(pts
						(arc
							(start -0.1778 -0.2794)
							(mid -0.249642 -0.249642)
							(end -0.2794 -0.1778)
						)
						(arc
							(start -0.2794 0.1778)
							(mid -0.249642 0.249642)
							(end -0.1778 0.2794)
						)
						(arc
							(start 0.1778 0.2794)
							(mid 0.249642 0.249642)
							(end 0.2794 0.1778)
						)
						(arc
							(start 0.2794 -0.1778)
							(mid 0.249642 -0.249642)
							(end 0.1778 -0.2794)
						)
					)
					(width 0)
					(fill yes)
				)
			)
		)
	)
	(footprint ""
		(layer "F.Cu")
		(at 219.8878 -393.5984 180)
		(property "Reference" "C130"
			(at 0 0 180)
			(layer "F.SilkS")
			(hide yes)
			(effects
				(font
					(size 1.27 1.27)
				)
			)
		)
		(property "Value" "SC1U25V3KX-1-GP"
			(at 0 -2.8194 180)
			(unlocked yes)
			(layer "F.Fab")
			(hide yes)
			(effects
				(font
					(size 1.016 1.016)
					(thickness 0.1524)
				)
			)
		)
		(property "Device Type" "C603H36"
			(at 0 -4.3434 180)
			(unlocked yes)
			(layer "F.Fab")
			(hide yes)
			(effects
				(font
					(size 1.016 1.016)
					(thickness 0.1524)
				)
			)
		)
		(duplicate_pad_numbers_are_jumpers no)
		(fp_line
			(start 0.508 0)
			(end -0.508 0)
			(stroke
				(width 0.2032)
				(type default)
			)
			(layer "F.SilkS")
		)
		(fp_rect
			(start -0.5842 1.3335)
			(end 0.5842 -1.3335)
			(stroke
				(width 0)
				(type default)
			)
			(fill no)
			(layer "F.CrtYd")
		)
		(fp_rect
			(start -0.5842 1.3335)
			(end 0.5842 -1.3335)
			(stroke
				(width 0)
				(type default)
			)
			(fill no)
			(layer "F.Fab")
		)
		(pad "1" smd custom
			(at 0 -0.762 180)
			(size 0.2159 0.2159)
			(layers "F.Cu" "F.Mask" "F.Paste")
			(net "P12V_HDD1")
			(options
				(clearance outline)
				(anchor circle)
			)
			(primitives
				(gr_poly
					(pts
						(arc
							(start -0.3302 -0.4318)
							(mid -0.402042 -0.402042)
							(end -0.4318 -0.3302)
						)
						(arc
							(start -0.4318 0.3302)
							(mid -0.402042 0.402042)
							(end -0.3302 0.4318)
						)
						(arc
							(start 0.3302 0.4318)
							(mid 0.402042 0.402042)
							(end 0.4318 0.3302)
						)
						(arc
							(start 0.4318 -0.3302)
							(mid 0.402042 -0.402042)
							(end 0.3302 -0.4318)
						)
					)
					(width 0)
					(fill yes)
				)
			)
		)
		(pad "2" smd custom
			(at 0 0.762 180)
			(size 0.2159 0.2159)
			(layers "F.Cu" "F.Mask" "F.Paste")
			(net "GND")
			(options
				(clearance outline)
				(anchor circle)
			)
			(primitives
				(gr_poly
					(pts
						(arc
							(start -0.3302 -0.4318)
							(mid -0.402042 -0.402042)
							(end -0.4318 -0.3302)
						)
						(arc
							(start -0.4318 0.3302)
							(mid -0.402042 0.402042)
							(end -0.3302 0.4318)
						)
						(arc
							(start 0.3302 0.4318)
							(mid 0.402042 0.402042)
							(end 0.4318 0.3302)
						)
						(arc
							(start 0.4318 -0.3302)
							(mid 0.402042 -0.402042)
							(end 0.3302 -0.4318)
						)
					)
					(width 0)
					(fill yes)
				)
			)
		)
	)
	(footprint ""
		(layer "F.Cu")
		(at 43.306746 -205.895702 180)
		(property "Reference" "R470"
			(at 0 0 180)
			(layer "F.SilkS")
			(hide yes)
			(effects
				(font
					(size 1.27 1.27)
				)
			)
		)
		(property "Value" "4K7R2J-2-GP"
			(at 0.064008 -3.993896 180)
			(unlocked yes)
			(layer "F.Fab")
			(hide yes)
			(effects
				(font
					(size 1.016 1.016)
					(thickness 0.1524)
				)
			)
		)
		(property "Device Type" "R402H16"
			(at 0.064008 -5.517896 180)
			(unlocked yes)
			(layer "F.Fab")
			(hide yes)
			(effects
				(font
					(size 1.016 1.016)
					(thickness 0.1524)
				)
			)
		)
		(duplicate_pad_numbers_are_jumpers no)
		(fp_line
			(start 0.508 -0.9398)
			(end -0.508 -0.9398)
			(stroke
				(width 0.1524)
				(type default)
			)
			(layer "F.SilkS")
		)
		(fp_line
			(start -0.508 -0.9398)
			(end -0.508 0.9398)
			(stroke
				(width 0.1524)
				(type default)
			)
			(layer "F.SilkS")
		)
		(fp_rect
			(start -0.508 0.9398)
			(end 0.508 -0.9398)
			(stroke
				(width 0)
				(type default)
			)
			(fill no)
			(layer "F.CrtYd")
		)
		(fp_rect
			(start -0.508 0.9398)
			(end 0.508 -0.9398)
			(stroke
				(width 0)
				(type default)
			)
			(fill no)
			(layer "F.Fab")
		)
		(pad "1" smd custom
			(at 0 -0.4445 180)
			(size 0.1397 0.1397)
			(layers "F.Cu" "F.Mask" "F.Paste")
			(net "P3V3")
			(options
				(clearance outline)
				(anchor circle)
			)
			(primitives
				(gr_poly
					(pts
						(arc
							(start -0.1778 -0.2794)
							(mid -0.249642 -0.249642)
							(end -0.2794 -0.1778)
						)
						(arc
							(start -0.2794 0.1778)
							(mid -0.249642 0.249642)
							(end -0.1778 0.2794)
						)
						(arc
							(start 0.1778 0.2794)
							(mid 0.249642 0.249642)
							(end 0.2794 0.1778)
						)
						(arc
							(start 0.2794 -0.1778)
							(mid 0.249642 -0.249642)
							(end 0.1778 -0.2794)
						)
					)
					(width 0)
					(fill yes)
				)
			)
		)
		(pad "2" smd custom
			(at 0 0.4445 180)
			(size 0.1397 0.1397)
			(layers "F.Cu" "F.Mask" "F.Paste")
			(net "SAS_EXP_A_PWR12")
			(options
				(clearance outline)
				(anchor circle)
			)
			(primitives
				(gr_poly
					(pts
						(arc
							(start -0.1778 -0.2794)
							(mid -0.249642 -0.249642)
							(end -0.2794 -0.1778)
						)
						(arc
							(start -0.2794 0.1778)
							(mid -0.249642 0.249642)
							(end -0.1778 0.2794)
						)
						(arc
							(start 0.1778 0.2794)
							(mid 0.249642 0.249642)
							(end 0.2794 0.1778)
						)
						(arc
							(start 0.2794 -0.1778)
							(mid 0.249642 -0.249642)
							(end 0.1778 -0.2794)
						)
					)
					(width 0)
					(fill yes)
				)
			)
		)
	)
	(footprint ""
		(layer "F.Cu")
		(at 39.750746 -40.9067 90)
		(property "Reference" "R229"
			(at 0 0 90)
			(layer "F.SilkS")
			(hide yes)
			(effects
				(font
					(size 1.27 1.27)
				)
			)
		)
		(property "Value" "330R2F-GP"
			(at 0.064008 -3.993896 90)
			(unlocked yes)
			(layer "F.Fab")
			(hide yes)
			(effects
				(font
					(size 1.016 1.016)
					(thickness 0.1524)
				)
			)
		)
		(property "Device Type" "R402H16"
			(at 0.064008 -5.517896 90)
			(unlocked yes)
			(layer "F.Fab")
			(hide yes)
			(effects
				(font
					(size 1.016 1.016)
					(thickness 0.1524)
				)
			)
		)
		(duplicate_pad_numbers_are_jumpers no)
		(fp_line
			(start 0.508 -0.9398)
			(end -0.508 -0.9398)
			(stroke
				(width 0.1524)
				(type default)
			)
			(layer "F.SilkS")
		)
		(fp_line
			(start -0.508 -0.9398)
			(end -0.508 0.9398)
			(stroke
				(width 0.1524)
				(type default)
			)
			(layer "F.SilkS")
		)
		(fp_rect
			(start -0.508 0.9398)
			(end 0.508 -0.9398)
			(stroke
				(width 0)
				(type default)
			)
			(fill no)
			(layer "F.CrtYd")
		)
		(fp_rect
			(start -0.508 0.9398)
			(end 0.508 -0.9398)
			(stroke
				(width 0)
				(type default)
			)
			(fill no)
			(layer "F.Fab")
		)
		(pad "1" smd custom
			(at 0 -0.4445 90)
			(size 0.1397 0.1397)
			(layers "F.Cu" "F.Mask" "F.Paste")
			(net "P3V3_HDD9_LED")
			(options
				(clearance outline)
				(anchor circle)
			)
			(primitives
				(gr_poly
					(pts
						(arc
							(start -0.1778 -0.2794)
							(mid -0.249642 -0.249642)
							(end -0.2794 -0.1778)
						)
						(arc
							(start -0.2794 0.1778)
							(mid -0.249642 0.249642)
							(end -0.1778 0.2794)
						)
						(arc
							(start 0.1778 0.2794)
							(mid 0.249642 0.249642)
							(end 0.2794 0.1778)
						)
						(arc
							(start 0.2794 -0.1778)
							(mid 0.249642 -0.249642)
							(end 0.1778 -0.2794)
						)
					)
					(width 0)
					(fill yes)
				)
			)
		)
		(pad "2" smd custom
			(at 0 0.4445 90)
			(size 0.1397 0.1397)
			(layers "F.Cu" "F.Mask" "F.Paste")
			(net "FLT_HDD9")
			(options
				(clearance outline)
				(anchor circle)
			)
			(primitives
				(gr_poly
					(pts
						(arc
							(start -0.1778 -0.2794)
							(mid -0.249642 -0.249642)
							(end -0.2794 -0.1778)
						)
						(arc
							(start -0.2794 0.1778)
							(mid -0.249642 0.249642)
							(end -0.1778 0.2794)
						)
						(arc
							(start 0.1778 0.2794)
							(mid 0.249642 0.249642)
							(end 0.2794 0.1778)
						)
						(arc
							(start 0.2794 -0.1778)
							(mid 0.249642 -0.249642)
							(end 0.1778 -0.2794)
						)
					)
					(width 0)
					(fill yes)
				)
			)
		)
	)
	(footprint ""
		(layer "F.Cu")
		(at 190.627 -190.373)
		(property "Reference" "R149"
			(at 0 0 0)
			(layer "F.SilkS")
			(hide yes)
			(effects
				(font
					(size 1.27 1.27)
				)
			)
		)
		(property "Value" "200KR2F-L-GP"
			(at 0.064008 -3.993896 0)
			(unlocked yes)
			(layer "F.Fab")
			(hide yes)
			(effects
				(font
					(size 1.016 1.016)
					(thickness 0.1524)
				)
			)
		)
		(property "Device Type" "R402H16"
			(at 0.064008 -5.517896 0)
			(unlocked yes)
			(layer "F.Fab")
			(hide yes)
			(effects
				(font
					(size 1.016 1.016)
					(thickness 0.1524)
				)
			)
		)
		(duplicate_pad_numbers_are_jumpers no)
		(fp_line
			(start -0.508 -0.9398)
			(end -0.508 0.9398)
			(stroke
				(width 0.1524)
				(type default)
			)
			(layer "F.SilkS")
		)
		(fp_line
			(start 0.508 -0.9398)
			(end -0.508 -0.9398)
			(stroke
				(width 0.1524)
				(type default)
			)
			(layer "F.SilkS")
		)
		(fp_rect
			(start -0.508 0.9398)
			(end 0.508 -0.9398)
			(stroke
				(width 0)
				(type default)
			)
			(fill no)
			(layer "F.CrtYd")
		)
		(fp_rect
			(start -0.508 0.9398)
			(end 0.508 -0.9398)
			(stroke
				(width 0)
				(type default)
			)
			(fill no)
			(layer "F.Fab")
		)
		(pad "1" smd custom
			(at 0 -0.4445)
			(size 0.1397 0.1397)
			(layers "F.Cu" "F.Mask" "F.Paste")
			(net "P12V")
			(options
				(clearance outline)
				(anchor circle)
			)
			(primitives
				(gr_poly
					(pts
						(arc
							(start -0.1778 -0.2794)
							(mid -0.249642 -0.249642)
							(end -0.2794 -0.1778)
						)
						(arc
							(start -0.2794 0.1778)
							(mid -0.249642 0.249642)
							(end -0.1778 0.2794)
						)
						(arc
							(start 0.1778 0.2794)
							(mid 0.249642 0.249642)
							(end 0.2794 0.1778)
						)
						(arc
							(start 0.2794 -0.1778)
							(mid 0.249642 -0.249642)
							(end 0.1778 -0.2794)
						)
					)
					(width 0)
					(fill yes)
				)
			)
		)
		(pad "2" smd custom
			(at 0 0.4445)
			(size 0.1397 0.1397)
			(layers "F.Cu" "F.Mask" "F.Paste")
			(net "SW_HDD3_P")
			(options
				(clearance outline)
				(anchor circle)
			)
			(primitives
				(gr_poly
					(pts
						(arc
							(start -0.1778 -0.2794)
							(mid -0.249642 -0.249642)
							(end -0.2794 -0.1778)
						)
						(arc
							(start -0.2794 0.1778)
							(mid -0.249642 0.249642)
							(end -0.1778 0.2794)
						)
						(arc
							(start 0.1778 0.2794)
							(mid 0.249642 0.249642)
							(end 0.2794 0.1778)
						)
						(arc
							(start 0.2794 -0.1778)
							(mid 0.249642 -0.249642)
							(end 0.1778 -0.2794)
						)
					)
					(width 0)
					(fill yes)
				)
			)
		)
	)
	(footprint ""
		(layer "F.Cu")
		(at 213.741 -393.9032 180)
		(property "Reference" "C127"
			(at 0 0 180)
			(layer "F.SilkS")
			(hide yes)
			(effects
				(font
					(size 1.27 1.27)
				)
			)
		)
		(property "Value" "SC10U25V6KX-1GP"
			(at -0.0762 -5.1308 180)
			(unlocked yes)
			(layer "F.Fab")
			(hide yes)
			(effects
				(font
					(size 1.016 1.016)
					(thickness 0.1524)
				)
			)
		)
		(property "Device Type" "C1206H71"
			(at -0.127 -6.6548 180)
			(unlocked yes)
			(layer "F.Fab")
			(hide yes)
			(effects
				(font
					(size 1.016 1.016)
					(thickness 0.1524)
				)
			)
		)
		(duplicate_pad_numbers_are_jumpers no)
		(fp_line
			(start 1.016 2.2352)
			(end -1.016 2.2352)
			(stroke
				(width 0.1524)
				(type default)
			)
			(layer "F.SilkS")
		)
		(fp_line
			(start 1.016 0.8382)
			(end 1.016 2.2352)
			(stroke
				(width 0.1524)
				(type default)
			)
			(layer "F.SilkS")
		)
		(fp_line
			(start 1.016 -2.2352)
			(end 1.016 -0.8382)
			(stroke
				(width 0.1524)
				(type default)
			)
			(layer "F.SilkS")
		)
		(fp_line
			(start -1.016 2.2352)
			(end -1.016 0.8382)
			(stroke
				(width 0.1524)
				(type default)
			)
			(layer "F.SilkS")
		)
		(fp_line
			(start -1.016 -0.8382)
			(end -1.016 -2.2352)
			(stroke
				(width 0.1524)
				(type default)
			)
			(layer "F.SilkS")
		)
		(fp_line
			(start -1.016 -2.2352)
			(end 1.016 -2.2352)
			(stroke
				(width 0.1524)
				(type default)
			)
			(layer "F.SilkS")
		)
		(fp_rect
			(start -1.0922 2.3114)
			(end 1.0922 -2.3114)
			(stroke
				(width 0)
				(type default)
			)
			(fill no)
			(layer "F.CrtYd")
		)
		(fp_poly
			(pts
				(xy 1.0922 -2.3114) (xy 1.0922 2.3114) (xy -1.0922 2.3114) (xy -1.0922 -2.3114)
			)
			(stroke
				(width 0)
				(type default)
			)
			(fill no)
			(layer "F.Fab")
		)
		(pad "1" smd rect
			(at 0 -1.397 180)
			(size 1.651 1.27)
			(layers "F.Cu" "F.Mask" "F.Paste")
			(net "P12V_HDD1")
		)
		(pad "2" smd rect
			(at 0 1.397 180)
			(size 1.651 1.27)
			(layers "F.Cu" "F.Mask" "F.Paste")
			(net "GND")
		)
	)
	(footprint ""
		(layer "F.Cu")
		(at 78.867 -402.463)
		(property "Reference" "R569"
			(at 0 0 0)
			(layer "F.SilkS")
			(hide yes)
			(effects
				(font
					(size 1.27 1.27)
				)
			)
		)
		(property "Value" "300KR2F-GP"
			(at 0.064008 -3.993896 0)
			(unlocked yes)
			(layer "F.Fab")
			(hide yes)
			(effects
				(font
					(size 1.016 1.016)
					(thickness 0.1524)
				)
			)
		)
		(property "Device Type" "R402H16"
			(at 0.064008 -5.517896 0)
			(unlocked yes)
			(layer "F.Fab")
			(hide yes)
			(effects
				(font
					(size 1.016 1.016)
					(thickness 0.1524)
				)
			)
		)
		(duplicate_pad_numbers_are_jumpers no)
		(fp_line
			(start -0.508 -0.9398)
			(end -0.508 0.9398)
			(stroke
				(width 0.1524)
				(type default)
			)
			(layer "F.SilkS")
		)
		(fp_line
			(start 0.508 -0.9398)
			(end -0.508 -0.9398)
			(stroke
				(width 0.1524)
				(type default)
			)
			(layer "F.SilkS")
		)
		(fp_rect
			(start -0.508 0.9398)
			(end 0.508 -0.9398)
			(stroke
				(width 0)
				(type default)
			)
			(fill no)
			(layer "F.CrtYd")
		)
		(fp_rect
			(start -0.508 0.9398)
			(end 0.508 -0.9398)
			(stroke
				(width 0)
				(type default)
			)
			(fill no)
			(layer "F.Fab")
		)
		(pad "1" smd custom
			(at 0 -0.4445)
			(size 0.1397 0.1397)
			(layers "F.Cu" "F.Mask" "F.Paste")
			(net "SW_HDD6_N")
			(options
				(clearance outline)
				(anchor circle)
			)
			(primitives
				(gr_poly
					(pts
						(arc
							(start -0.1778 -0.2794)
							(mid -0.249642 -0.249642)
							(end -0.2794 -0.1778)
						)
						(arc
							(start -0.2794 0.1778)
							(mid -0.249642 0.249642)
							(end -0.1778 0.2794)
						)
						(arc
							(start 0.1778 0.2794)
							(mid 0.249642 0.249642)
							(end 0.2794 0.1778)
						)
						(arc
							(start 0.2794 -0.1778)
							(mid 0.249642 -0.249642)
							(end 0.1778 -0.2794)
						)
					)
					(width 0)
					(fill yes)
				)
			)
		)
		(pad "2" smd custom
			(at 0 0.4445)
			(size 0.1397 0.1397)
			(layers "F.Cu" "F.Mask" "F.Paste")
			(net "P12V")
			(options
				(clearance outline)
				(anchor circle)
			)
			(primitives
				(gr_poly
					(pts
						(arc
							(start -0.1778 -0.2794)
							(mid -0.249642 -0.249642)
							(end -0.2794 -0.1778)
						)
						(arc
							(start -0.2794 0.1778)
							(mid -0.249642 0.249642)
							(end -0.1778 0.2794)
						)
						(arc
							(start 0.1778 0.2794)
							(mid 0.249642 0.249642)
							(end 0.2794 0.1778)
						)
						(arc
							(start 0.2794 -0.1778)
							(mid 0.249642 -0.249642)
							(end 0.1778 -0.2794)
						)
					)
					(width 0)
					(fill yes)
				)
			)
		)
	)
)
